FILE_TYPE = CONNECTIVITY;
{Allegro Design Entry HDL 17.2-2016 S081 (4005846) 1/11/2022}
"PAGE_NUMBER" = 198;
0"NC";
1"GND\g";
2"GND\g";
3"GND\g";
4"GND\g";
5"GND\g";
6"GND\g";
7"GND\g";
8"GND\g";
9"GND\g";
10"GND\g";
11"GND\g";
12"IND_PVDDIO_P1_CPL0";
13"SW_PVDDIO_P1_SW4";
14"SW_PVDDIO_P1_BOOTR4";
15"SW_P12V_STBY_PVDDIO_P1_FLT\g";
16"PVDDIO_P1\g";
17"GND\g";
18"PVDDIO_P1\g";
19"GND\g";
20"SW_P12V_STBY_PVDDIO_P1_FLT\g";
21"GND\g";
22"GND\g";
23"GND\g";
24"GND\g";
25"PVDDCR_CPU1_P1_PVCC\g";
26"PVDDCR_CPU1_P1_PVCC\g";
27"SW_PVDDIO_P1_BOOT4";
28"PVDDIO_P1_VOS4";
29"PVDDIO_P1_LSET4";
30"SW_PVDDIO_P1_BOOTR3";
31"SW_PVDDIO_P1_SW3";
32"PVDDIO_P1_VCC4"CDS_PHYS_NET_NAME"PVCCFA_EHV_FIVRA_CPU0_VDD2";
33"NC_PVDDIO_P1_DNC4";
34"PVDDCR_CPU1_P1_VCCS"CDS_PHYS_NET_NAME"PVCCIN_CPU0_VREF";
35"PVDDIO_P1_PWM4";
36"PVDDIO_P1_TEMP1";
37"PVDDIO_P1_IMON4";
38"NC_PVDDIO_P1_GL2_4";
39"NC_PVDDIO_P1_GL1_4";
40"PVDDIO_P1_VCC3"CDS_PHYS_NET_NAME"PVCCFA_EHV_FIVRA_CPU0_VDD1";
41"NC_PVDDIO_P1_DNC3";
42"PVDDCR_CPU1_P1_VCCS"CDS_PHYS_NET_NAME"PVCCIN_CPU0_VREF";
43"PVDDIO_P1_LSET3"CDS_PHYS_NET_NAME"PVCCFA_EHV_FIVRA_CPU0_LSET1";
44"PVDDIO_P1_PWM3";
45"PVDDIO_P1_TEMP1";
46"PVDDIO_P1_IMON3";
47"NC_PVDDIO_P1_GL1_3";
48"NC_PVDDIO_P1_GL2_3";
49"PVDDIO_P1_VOS3";
50"SW_PVDDIO_P1_BOOT3";
51"SW_PVDDIO_P1_SW4_RC";
52"SW_PVDDIO_P1_BOOT4_R";
53"IND_PVDDIO_P1_CPL4";
54"SW_PVDDIO_P1_SW3_RC";
55"IND_PVDDIO_P1_CPL4";
56"SW_PVDDIO_P1_BOOT3_R";
57"IND_PVDDIO_P1_CPL3";
%"UNIVERSAL_GND"
"1","(-11525,1600)","0","pure_quanta_power","I1";
;
CDS_LIB"pure_quanta_power"
HDL_POWER"GND";
"A"1;
%"Q_CAP"
"1","(-8650,6075)","0","pure_quanta","I100";
;
LOCATION"PC622_3"
$SEC"1"
CDS_SEC"1"
MATERIAL"X7R"
TOLERANCE"10%"
VALUE"0.1UF"
PART_NUMBER"CH4104K1B00"
VOLTAGE"25V"
PACK_TYPE"0402"
CDS_LIB"pure_quanta";
"B"
$PN"2"21;
"A"
$PN"1"20;
%"Q_CAP"
"1","(-8625,3300)","0","pure_quanta","I101";
;
LOCATION"PC623_4"
$SEC"1"
CDS_SEC"1"
MATERIAL"X7R"
TOLERANCE"10%"
VALUE"0.1UF"
PART_NUMBER"CH4104K1B00"
VOLTAGE"25V"
PACK_TYPE"0402"
CDS_LIB"pure_quanta";
"B"
$PN"2"22;
"A"
$PN"1"15;
%"Q_CAP"
"1","(-11175,5425)","0","pure_quanta","I102";
;
LOCATION"PC617"
$SEC"1"
CDS_SEC"1"
MATERIAL"X6S"
TOLERANCE"10%"
VALUE"2.2UF"
PART_NUMBER"CH5222KEB01"
VOLTAGE"10V"
PACK_TYPE"C0402"
CDS_LIB"pure_quanta";
"B"
$PN"2"2;
"A"
$PN"1"40;
%"UNIVERSAL_GND"
"1","(-11175,5225)","0","pure_quanta_power","I103";
;
CDS_LIB"pure_quanta_power"
HDL_POWER"GND";
"A"2;
%"UNIVERSAL_GND"
"1","(-10825,5725)","0","pure_quanta_power","I104";
;
CDS_LIB"pure_quanta_power"
HDL_POWER"GND";
"A"3;
%"Q_RES"
"2","(-11175,5975)","0","pure_quanta","I105";
;
LOCATION"PR371"
$SEC"1"
CDS_SEC"1"
WATTAGE"1/16W"
MATERIAL"CHIP"
TOLERANCE"1%"
VALUE"2.2"
PART_NUMBER"CS-2202FB00"
PACK_TYPE"0402LF"
CDS_LIB"pure_quanta";
"A"
$PN"1"26;
"B"
$PN"2"40;
%"Q_CAP"
"1","(-10825,6000)","0","pure_quanta","I106";
;
LOCATION"PC619_IOP1_3"
$SEC"1"
CDS_SEC"1"
MATERIAL"X6S"
TOLERANCE"10%"
VALUE"2.2UF"
PART_NUMBER"CH5222KEB01"
VOLTAGE"10V"
PACK_TYPE"C0402"
CDS_LIB"pure_quanta";
"B"
$PN"2"3;
"A"
$PN"1"26;
%"Q_CAP"
"1","(-11200,2725)","0","pure_quanta","I108";
;
LOCATION"PC616"
$SEC"1"
CDS_SEC"1"
MATERIAL"X6S"
TOLERANCE"10%"
VALUE"2.2UF"
PART_NUMBER"CH5222KEB01"
VOLTAGE"10V"
PACK_TYPE"C0402"
CDS_LIB"pure_quanta";
"B"
$PN"2"4;
"A"
$PN"1"32;
%"UNIVERSAL_GND"
"1","(-11200,2525)","0","pure_quanta_power","I109";
;
CDS_LIB"pure_quanta_power"
HDL_POWER"GND";
"A"4;
%"UNIVERSAL_GND"
"1","(-10850,3025)","0","pure_quanta_power","I110";
;
CDS_LIB"pure_quanta_power"
HDL_POWER"GND";
"A"5;
%"Q_RES"
"2","(-11200,3275)","0","pure_quanta","I111";
;
LOCATION"PR370"
$SEC"1"
CDS_SEC"1"
WATTAGE"1/16W"
MATERIAL"CHIP"
TOLERANCE"1%"
VALUE"2.2"
PART_NUMBER"CS-2202FB00"
PACK_TYPE"0402LF"
CDS_LIB"pure_quanta";
"A"
$PN"1"25;
"B"
$PN"2"32;
%"Q_CAP"
"1","(-10850,3300)","0","pure_quanta","I112";
;
LOCATION"PC618_IOP1_4"
$SEC"1"
CDS_SEC"1"
MATERIAL"X6S"
TOLERANCE"10%"
VALUE"2.2UF"
PART_NUMBER"CH5222KEB01"
VOLTAGE"10V"
PACK_TYPE"C0402"
CDS_LIB"pure_quanta";
"B"
$PN"2"5;
"A"
$PN"1"25;
%"UNIVERSAL_GND"
"1","(-12050,4550)","0","pure_quanta_power","I114";
;
CDS_LIB"pure_quanta_power"
HDL_POWER"GND";
"A"6;
%"UNIVERSAL_GND"
"1","(-12075,1750)","0","pure_quanta_power","I115";
;
CDS_LIB"pure_quanta_power"
HDL_POWER"GND";
"A"7;
%"UNIVERSAL_GND"
"1","(-8075,4200)","0","pure_quanta_power","I117";
;
CDS_LIB"pure_quanta_power"
HDL_POWER"GND";
"A"8;
%"Q_RES"
"2","(-8075,4425)","0","pure_quanta","I118";
;
LOCATION"PR492"
$SEC"1"
CDS_SEC"1"
WATTAGE"1/8W"
MATERIAL"EMPTY"
TOLERANCE"1%"
VALUE"1.5"
PART_NUMBER"CS-1504FB00"
PACK_TYPE"0402LF"
CDS_LIB"pure_quanta";
"A"
$PN"1"54;
"B"
$PN"2"8;
%"Q_CAP"
"1","(-8075,4925)","0","pure_quanta","I119";
;
LOCATION"PC177"
$SEC"1"
CDS_SEC"1"
MATERIAL"EMPTY"
TOLERANCE"10%"
VALUE"560PF"
PART_NUMBER"CH1566K1B09"
VOLTAGE"50V"
PACK_TYPE"C0402"
CDS_LIB"pure_quanta";
"B"
$PN"2"54;
"A"
$PN"1"31;
%"UNIVERSAL_GND"
"1","(-8175,1400)","0","pure_quanta_power","I120";
;
CDS_LIB"pure_quanta_power"
HDL_POWER"GND";
"A"9;
%"Q_RES"
"2","(-8175,1625)","0","pure_quanta","I121";
;
LOCATION"PR491"
$SEC"1"
CDS_SEC"1"
WATTAGE"1/8W"
MATERIAL"EMPTY"
TOLERANCE"1%"
VALUE"1.5"
PART_NUMBER"CS-1504FB00"
PACK_TYPE"0402LF"
CDS_LIB"pure_quanta";
"A"
$PN"1"51;
"B"
$PN"2"9;
%"Q_CAP"
"1","(-8175,2125)","0","pure_quanta","I122";
;
LOCATION"PC176"
$SEC"1"
CDS_SEC"1"
TOLERANCE"10%"
VALUE"560PF"
PACK_TYPE"C0402"
VOLTAGE"50V"
PART_NUMBER"CH1566K1B09"
MATERIAL"EMPTY"
CDS_LIB"pure_quanta";
"B"
$PN"2"51;
"A"
$PN"1"13;
%"VCC_CORE"
"1","(-11175,6375)","0","pure_quanta_power","I123";
;
HDL_POWER"PVDDCR_CPU1_P1_PVCC"
CDS_LIB"pure_quanta_power";
"A"26;
%"VCC_CORE"
"1","(-11200,3675)","0","pure_quanta_power","I124";
;
HDL_POWER"PVDDCR_CPU1_P1_PVCC"
CDS_LIB"pure_quanta_power";
"A"25;
%"Q_INDUCTOR"
"1","(-7450,2100)","2","pure_quanta","I128";
;
LOCATION"PL46"
$SEC"1"
CDS_SEC"1"
MATERIAL"IND"
PART_NUMBER"CV+22Y0EZ00"
VALUE"0.22UH/33A"
PACK_TYPE"SMLF"
CDS_LIB"pure_quanta"
NEEDS_NO_SIZE"TRUE";
"1"
$PN"1"12;
"2"
$PN"2"10;
%"UNIVERSAL_GND"
"1","(-7750,1975)","0","pure_quanta_power","I129";
;
CDS_LIB"pure_quanta_power"
HDL_POWER"GND";
"A"10;
%"UNIVERSAL_GND"
"1","(-11500,4450)","0","pure_quanta_power","I14";
;
CDS_LIB"pure_quanta_power"
HDL_POWER"GND";
"A"11;
%"Q_RES"
"2","(-11500,4675)","2","pure_quanta","I15";
;
LOCATION"PR369"
$SEC"1"
CDS_SEC"1"
WATTAGE"1/16W"
MATERIAL"EMPTY"
TOLERANCE"1%"
VALUE"8.87K"
PART_NUMBER"CS28872FB01"
PACK_TYPE"0402LF"
CDS_LIB"pure_quanta";
"A"
$PN"1"43;
"B"
$PN"2"11;
%"Q_RES"
"2","(-11525,1825)","2","pure_quanta","I2";
;
LOCATION"PR368"
$SEC"1"
CDS_SEC"1"
WATTAGE"1/16W"
MATERIAL"EMPTY"
TOLERANCE"1%"
VALUE"8.87K"
PART_NUMBER"CS28872FB01"
PACK_TYPE"0402LF"
CDS_LIB"pure_quanta";
"A"
$PN"1"29;
"B"
$PN"2"1;
%"ISL99390FRZTR5935"
"1","(-9500,2325)","0","pure_quanta","I23";
;
LOCATION"PU53"
$SEC"1"
CDS_SEC"1"
PART_TYPE"SMLF"
MATERIAL"IC"
VALUE"ISL99390FRZ-TR5935"
PART_NUMBER"AL099390004"
CDS_LIB"pure_quanta"
CDS_LMAN_SYM_OUTLINE"-300,700,250,-650"
NEEDS_NO_SIZE"TRUE";
"PGND2"
$PN"7_9-20_24"24;
"GL2"
$PN"41"38;
"GL1"
$PN"6"39;
"DNC"
$PN"31"33;
"EN"
$PN"35"32;
"PGND3"
$PN"40"24;
"VOS"
$PN"1"28;
"VIN2"
$PN"30"15;
"PGND1"
$PN"5"24;
"SW"
$PN"10_19"13;
"LSET"
$PN"37"29;
"IOUT"
$PN"38"37;
"TOUT_FLT"
$PN"36"36;
"PVCC"
$PN"4"25;
"PHASE"
$PN"32"14;
"VIN1"
$PN"25_29"15;
"BOOT"
$PN"33"27;
"AGND"
$PN"2"24;
"VCC"
$PN"3"32;
"REFIN"
$PN"39"34;
"PWM"
$PN"34"35;
%"UNIVERSAL_GND"
"1","(-8850,1600)","0","pure_quanta_power","I24";
;
CDS_LIB"pure_quanta_power"
HDL_POWER"GND";
"A"24;
%"ISL99390FRZTR5935"
"1","(-9500,5125)","0","pure_quanta","I26";
;
LOCATION"PU52"
$SEC"1"
CDS_SEC"1"
PART_TYPE"SMLF"
MATERIAL"IC"
VALUE"ISL99390FRZ-TR5935"
PART_NUMBER"AL099390004"
CDS_LIB"pure_quanta"
CDS_LMAN_SYM_OUTLINE"-300,700,250,-650"
NEEDS_NO_SIZE"TRUE";
"PGND2"
$PN"7_9-20_24"23;
"GL2"
$PN"41"48;
"GL1"
$PN"6"47;
"DNC"
$PN"31"41;
"EN"
$PN"35"40;
"PGND3"
$PN"40"23;
"VOS"
$PN"1"49;
"VIN2"
$PN"30"20;
"PGND1"
$PN"5"23;
"SW"
$PN"10_19"31;
"LSET"
$PN"37"43;
"IOUT"
$PN"38"46;
"TOUT_FLT"
$PN"36"45;
"PVCC"
$PN"4"26;
"PHASE"
$PN"32"30;
"VIN1"
$PN"25_29"20;
"BOOT"
$PN"33"50;
"AGND"
$PN"2"23;
"VCC"
$PN"3"40;
"REFIN"
$PN"39"42;
"PWM"
$PN"34"44;
%"Q_CAP"
"1","(-8150,3275)","0","pure_quanta","I28";
;
LOCATION"PC625_4"
$SEC"1"
CDS_SEC"1"
MATERIAL"X6S"
TOLERANCE"10%"
VALUE"1UF"
PART_NUMBER"CH5104KEB02"
VOLTAGE"25V"
PACK_TYPE"C0402"
CDS_LIB"pure_quanta";
"B"
$PN"2"22;
"A"
$PN"1"15;
%"UNIVERSAL_GND"
"1","(-8850,4400)","0","pure_quanta_power","I29";
;
CDS_LIB"pure_quanta_power"
HDL_POWER"GND";
"A"23;
%"Q_CAP"
"1","(-8225,6075)","0","pure_quanta","I44";
;
LOCATION"PC624_3"
$SEC"1"
CDS_SEC"1"
MATERIAL"X6S"
TOLERANCE"10%"
VALUE"1UF"
PART_NUMBER"CH5104KEB02"
VOLTAGE"25V"
PACK_TYPE"C0402"
CDS_LIB"pure_quanta";
"B"
$PN"2"21;
"A"
$PN"1"20;
%"Q_INDUCTOR4P_14"
"1","(-6425,2200)","0","pure_quanta","I46";
;
LOCATION"PL67"
$SEC"1"
CDS_SEC"1"
PART_TYPE"SMLF"
MATERIAL"IND"
PART_NUMBER"CV+15^0TZ04"
VALUE"150NH"
CDS_LIB"pure_quanta"
NEEDS_NO_SIZE"TRUE";
"1"
$PN"1"13;
"4"
$PN"4"18;
"3"
$PN"3"53;
"2"
$PN"2"12;
%"UNIVERSAL_GND"
"1","(-6875,2900)","0","pure_quanta_power","I49";
;
CDS_LIB"pure_quanta_power"
HDL_POWER"GND";
"A"22;
%"Q_CAP"
"1","(-7750,3275)","0","pure_quanta","I51";
;
LOCATION"PC627_4"
$SEC"1"
CDS_SEC"1"
MATERIAL"X6S"
TOLERANCE"10%"
VALUE"10UF"
VOLTAGE"25V"
PACK_TYPE"C0805"
PART_NUMBER"CH6104KEA00"
CDS_LIB"pure_quanta";
"B"
$PN"2"22;
"A"
$PN"1"15;
%"Q_CAP"
"1","(-7350,3275)","0","pure_quanta","I52";
;
LOCATION"PC629_4"
$SEC"1"
CDS_SEC"1"
MATERIAL"X6S"
TOLERANCE"10%"
VALUE"10UF"
PART_NUMBER"CH6104KEA00"
VOLTAGE"25V"
PACK_TYPE"C0805"
CDS_LIB"pure_quanta";
"B"
$PN"2"22;
"A"
$PN"1"15;
%"Q_CAP"
"1","(-6875,3275)","0","pure_quanta","I55";
;
LOCATION"PC633_4"
$SEC"1"
CDS_SEC"1"
TOLERANCE"10%"
VALUE"10UF"
VOLTAGE"25V"
PACK_TYPE"C0805"
PART_NUMBER"CH6104KEA00"
MATERIAL"X6S"
CDS_LIB"pure_quanta";
"B"
$PN"2"22;
"A"
$PN"1"15;
%"Q_RES"
"1","(-7100,4100)","0","pure_quanta","I57";
;
LOCATION"PR374"
$SEC"1"
CDS_SEC"1"
WATTAGE"1/16W"
MATERIAL"CHIP"
TOLERANCE"5%"
VALUE"0"
PART_NUMBER"CS00002JB38"
PACK_TYPE"0402LF"
CDS_LIB"pure_quanta";
"B"
$PN"2"16;
"A"
$PN"1"49;
%"Q_CAP"
"1","(-4625,2125)","0","pure_quanta","I59";
;
LOCATION"PC634_4"
$SEC"1"
CDS_SEC"1"
MATERIAL"X6S"
TOLERANCE"20%"
VALUE"22UF"
PART_NUMBER"TMP_QCH622KMEA01"
VOLTAGE"4V"
PACK_TYPE"0805"
CDS_LIB"pure_quanta";
"B"
$PN"2"19;
"A"
$PN"1"18;
%"Q_CAP"
"1","(-4300,4925)","0","pure_quanta","I65";
;
LOCATION"PC635_3"
$SEC"1"
CDS_SEC"1"
MATERIAL"X6S"
TOLERANCE"20%"
VALUE"22UF"
PART_NUMBER"TMP_QCH622KMEA01"
VOLTAGE"4V"
PACK_TYPE"0805"
CDS_LIB"pure_quanta";
"B"
$PN"2"17;
"A"
$PN"1"16;
%"Q_CAP"
"1","(-7825,6075)","0","pure_quanta","I67";
;
LOCATION"PC626_3"
$SEC"1"
CDS_SEC"1"
MATERIAL"X6S"
TOLERANCE"10%"
VALUE"10UF"
PART_NUMBER"CH6104KEA00"
VOLTAGE"25V"
PACK_TYPE"C0805"
CDS_LIB"pure_quanta";
"B"
$PN"2"21;
"A"
$PN"1"20;
%"Q_CAP"
"1","(-7425,6075)","0","pure_quanta","I68";
;
LOCATION"PC628_3"
$SEC"1"
CDS_SEC"1"
MATERIAL"X6S"
TOLERANCE"10%"
VALUE"10UF"
PART_NUMBER"CH6104KEA00"
VOLTAGE"25V"
PACK_TYPE"C0805"
CDS_LIB"pure_quanta";
"B"
$PN"2"21;
"A"
$PN"1"20;
%"Q_CAP"
"1","(-7100,5350)","0","pure_quanta","I69";
;
LOCATION"PC631"
$SEC"1"
CDS_SEC"1"
MATERIAL"X7R"
TOLERANCE"10%"
VALUE"0.22UF"
PART_NUMBER"CH4223K1B00"
VOLTAGE"16V"
PACK_TYPE"0402"
CDS_LIB"pure_quanta";
"B"
$PN"2"30;
"A"
$PN"1"56;
%"UNIVERSAL_GND"
"1","(-7000,5700)","0","pure_quanta_power","I70";
;
CDS_LIB"pure_quanta_power"
HDL_POWER"GND";
"A"21;
%"Q_CAP"
"1","(-7000,6100)","0","pure_quanta","I71";
;
LOCATION"PC632_3"
$SEC"1"
CDS_SEC"1"
MATERIAL"X6S"
TOLERANCE"10%"
VALUE"10UF"
PART_NUMBER"CH6104KEA00"
VOLTAGE"25V"
PACK_TYPE"C0805"
CDS_LIB"pure_quanta";
"B"
$PN"2"21;
"A"
$PN"1"20;
%"VCC_CORE"
"1","(-7000,6450)","0","pure_quanta_power","I72";
;
HDL_POWER"SW_P12V_STBY_PVDDIO_P1_FLT"
CDS_LIB"pure_quanta_power";
"A"20;
%"UNIVERSAL_GND"
"1","(-4200,1775)","0","pure_quanta_power","I77";
;
CDS_LIB"pure_quanta_power"
HDL_POWER"GND";
"A"19;
%"Q_CAP"
"1","(-4200,2125)","0","pure_quanta","I78";
;
LOCATION"PC636_4"
$SEC"1"
CDS_SEC"1"
MATERIAL"X6S"
TOLERANCE"20%"
VALUE"22UF"
PART_NUMBER"TMP_QCH622KMEA01"
VOLTAGE"4V"
PACK_TYPE"0805"
CDS_LIB"pure_quanta";
"B"
$PN"2"19;
"A"
$PN"1"18;
%"VCC_CORE"
"1","(-4200,2450)","0","pure_quanta_power","I79";
;
HDL_POWER"PVDDIO_P1"
CDS_LIB"pure_quanta_power";
"A"18;
%"Q_CAP"
"1","(-12075,1950)","0","pure_quanta","I8";
;
LOCATION"PC621_10"
$SEC"1"
CDS_SEC"1"
MATERIAL"X7R"
TOLERANCE"10%"
VALUE"0.1UF"
PART_NUMBER"CH4104K1B00"
VOLTAGE"25V"
PACK_TYPE"0402"
CDS_LIB"pure_quanta";
"B"
$PN"2"7;
"A"
$PN"1"34;
%"Q_CAP"
"1","(-3875,4925)","0","pure_quanta","I84";
;
LOCATION"PC637_3"
$SEC"1"
CDS_SEC"1"
MATERIAL"X6S"
TOLERANCE"20%"
VALUE"22UF"
PART_NUMBER"TMP_QCH622KMEA01"
VOLTAGE"4V"
PACK_TYPE"0805"
CDS_LIB"pure_quanta";
"B"
$PN"2"17;
"A"
$PN"1"16;
%"UNIVERSAL_GND"
"1","(-3875,4600)","0","pure_quanta_power","I85";
;
CDS_LIB"pure_quanta_power"
HDL_POWER"GND";
"A"17;
%"VCC_CORE"
"1","(-3875,5250)","0","pure_quanta_power","I86";
;
HDL_POWER"PVDDIO_P1"
CDS_LIB"pure_quanta_power";
"A"16;
%"VCC_CORE"
"1","(-6875,3650)","0","pure_quanta_power","I87";
;
HDL_POWER"SW_P12V_STBY_PVDDIO_P1_FLT"
CDS_LIB"pure_quanta_power";
"A"15;
%"Q_INDUCTOR4P_14"
"1","(-6175,5000)","0","pure_quanta","I93";
;
LOCATION"PL68"
$SEC"1"
CDS_SEC"1"
PART_TYPE"SMLF"
MATERIAL"IND"
VALUE"150NH"
PART_NUMBER"CV+15^0TZ04"
NEEDS_NO_SIZE"TRUE"
CDS_LIB"pure_quanta";
"1"
$PN"1"31;
"4"
$PN"4"16;
"3"
$PN"3"57;
"2"
$PN"2"55;
%"Q_CAP"
"1","(-7175,2550)","0","pure_quanta","I94";
;
LOCATION"PC630"
$SEC"1"
CDS_SEC"1"
MATERIAL"X7R"
TOLERANCE"10%"
VALUE"0.22UF"
VOLTAGE"16V"
PART_NUMBER"CH4223K1B00"
PACK_TYPE"0402"
CDS_LIB"pure_quanta";
"B"
$PN"2"14;
"A"
$PN"1"52;
%"Q_RES"
"1","(-6900,1300)","0","pure_quanta","I95";
;
LOCATION"PR375"
$SEC"1"
CDS_SEC"1"
WATTAGE"1/16W"
MATERIAL"CHIP"
TOLERANCE"5%"
VALUE"0"
PART_NUMBER"CS00002JB38"
PACK_TYPE"0402LF"
CDS_LIB"pure_quanta";
"B"
$PN"2"18;
"A"
$PN"1"28;
%"Q_CAP"
"1","(-12050,4750)","0","pure_quanta","I97";
;
LOCATION"PC620_9"
$SEC"1"
CDS_SEC"1"
MATERIAL"X7R"
TOLERANCE"10%"
VALUE"0.1UF"
PART_NUMBER"CH4104K1B00"
VOLTAGE"25V"
PACK_TYPE"0402"
CDS_LIB"pure_quanta";
"B"
$PN"2"6;
"A"
$PN"1"42;
%"Q_RES"
"1","(-8125,5475)","0","pure_quanta","I98";
;
LOCATION"PR373"
$SEC"1"
CDS_SEC"1"
PACK_TYPE"0402LF"
TOLERANCE"1%"
MATERIAL"CHIP"
WATTAGE"1/16W"
VALUE"4.7"
PART_NUMBER"CS-4702FB19"
CDS_LIB"pure_quanta";
"B"
$PN"2"56;
"A"
$PN"1"50;
%"Q_RES"
"1","(-8200,2675)","0","pure_quanta","I99";
;
LOCATION"PR372"
$SEC"1"
CDS_SEC"1"
PACK_TYPE"0402LF"
TOLERANCE"1%"
MATERIAL"CHIP"
WATTAGE"1/16W"
VALUE"4.7"
PART_NUMBER"CS-4702FB19"
CDS_LIB"pure_quanta";
"B"
$PN"2"52;
"A"
$PN"1"27;
END.
